(kicad_pcb
	(version 20260206)
	(generator "pcbnew")
	(generator_version "10.0")
	(general
		(thickness 1.6)
		(legacy_teardrops no)
	)
	(paper "A4")
	(title_block
		(title "Bryce Canyon_IOM_IOC_16318-2_OCP.brd")
		(comment 1 "Bryce Canyon / footprint 360 of 1605 (CN1), pads 75-148 of 202")
	)
	(layers
		(0 "F.Cu" signal "TOP")
		(4 "In1.Cu" signal "L2GND")
		(6 "In2.Cu" signal "L3")
		(8 "In3.Cu" signal "L4VCC")
		(10 "In4.Cu" signal "L5VCC")
		(12 "In5.Cu" signal "L6")
		(14 "In6.Cu" signal "L7GND")
		(2 "B.Cu" signal "BOTTOM")
		(9 "F.Adhes" user "F.Adhesive")
		(11 "B.Adhes" user "B.Adhesive")
		(13 "F.Paste" user "Package Geometry/Pastemask Top")
		(15 "B.Paste" user "Package Geometry/Pastemask Bottom")
		(5 "F.SilkS" user "Ref Des/Silkscreen Top")
		(7 "B.SilkS" user "Ref Des/Silkscreen Bottom")
		(1 "F.Mask" user "Board Geometry/Soldermask Top")
		(3 "B.Mask" user "Board Geometry/Soldermask Bottom")
		(17 "Dwgs.User" user "User.Drawings")
		(19 "Cmts.User" user "User.Comments")
		(21 "Eco1.User" user "User.Eco1")
		(23 "Eco2.User" user "User.Eco2")
		(25 "Edge.Cuts" user "Board Geometry/Outline")
		(27 "Margin" user)
		(31 "F.CrtYd" user "Package Geometry/Place Bound Top")
		(29 "B.CrtYd" user "Package Geometry/Place Bound Bottom")
		(35 "F.Fab" user "Ref Des/Assembly Top")
		(33 "B.Fab" user "Ref Des/Assembly Bottom")
	)
	(footprint ""
		(layer "F.Cu")
		(at 141.299946 -44.200064 180)
		(property "Reference" "CN1"
			(at 0 0 180)
			(layer "F.SilkS")
			(hide yes)
			(effects
				(font
					(size 1.27 1.27)
				)
			)
		)
		(property "Value" "AMP-CONN200-13R-4-GP"
			(at 30.332934 43.515534 180)
			(unlocked yes)
			(layer "F.Fab")
			(hide yes)
			(effects
				(font
					(size 1.016 1.016)
					(thickness 0.1524)
				)
			)
		)
		(property "Device Type" "PREFIT-200P-360520-1H542"
			(at 30.332934 41.991534 180)
			(unlocked yes)
			(layer "F.Fab")
			(hide yes)
			(effects
				(font
					(size 1.016 1.016)
					(thickness 0.1524)
				)
			)
		)
		(duplicate_pad_numbers_are_jumpers no)
		(pad "E9" thru_hole circle
			(at 21.599906 -7.199884 180)
			(size 0.762 0.762)
			(drill 0.359918)
			(layers "*.Cu" "*.Mask")
			(remove_unused_layers no)
			(net "PCIE_IOM_TO_COMP_16_DN")
			(clearance 0.1651)
			(thermal_gap 0.1651)
		)
		(pad "E10" thru_hole circle
			(at 23.400004 -5.999988 180)
			(size 0.762 0.762)
			(drill 0.359918)
			(layers "*.Cu" "*.Mask")
			(remove_unused_layers no)
			(net "PCIE_IOM_TO_COMP_17_DN")
			(clearance 0.1651)
			(thermal_gap 0.1651)
		)
		(pad "E11" thru_hole circle
			(at 25.200102 -7.199884 180)
			(size 0.762 0.762)
			(drill 0.359918)
			(layers "*.Cu" "*.Mask")
			(remove_unused_layers no)
			(net "PCIE_IOM_TO_COMP_18_DN")
			(clearance 0.1651)
			(thermal_gap 0.1651)
		)
		(pad "E12" thru_hole circle
			(at 26.999946 -5.999988 180)
			(size 0.762 0.762)
			(drill 0.359918)
			(layers "*.Cu" "*.Mask")
			(remove_unused_layers no)
			(net "PCIE_IOM_TO_COMP_19_DN")
			(clearance 0.1651)
			(thermal_gap 0.1651)
		)
		(pad "E13" thru_hole circle
			(at 28.800044 -7.199884 180)
			(size 0.762 0.762)
			(drill 0.359918)
			(layers "*.Cu" "*.Mask")
			(remove_unused_layers no)
			(net "PCIE_IOM_TO_COMP_20_DN")
			(clearance 0.1651)
			(thermal_gap 0.1651)
		)
		(pad "E14" thru_hole circle
			(at 30.599888 -5.999988 180)
			(size 0.762 0.762)
			(drill 0.359918)
			(layers "*.Cu" "*.Mask")
			(remove_unused_layers no)
			(net "PCIE_IOM_TO_COMP_21_DN")
			(clearance 0.1651)
			(thermal_gap 0.1651)
		)
		(pad "E15" thru_hole circle
			(at 32.399986 -7.199884 180)
			(size 0.762 0.762)
			(drill 0.359918)
			(layers "*.Cu" "*.Mask")
			(remove_unused_layers no)
			(net "PCIE_IOM_TO_COMP_22_DN")
			(clearance 0.1651)
			(thermal_gap 0.1651)
		)
		(pad "E16" thru_hole circle
			(at 34.200084 -5.999988 180)
			(size 0.762 0.762)
			(drill 0.359918)
			(layers "*.Cu" "*.Mask")
			(remove_unused_layers no)
			(net "PCIE_IOM_TO_COMP_23_DN")
			(clearance 0.1651)
			(thermal_gap 0.1651)
		)
		(pad "F1" thru_hole circle
			(at 0 -8.599932 180)
			(size 0.762 0.762)
			(drill 0.359918)
			(layers "*.Cu" "*.Mask")
			(remove_unused_layers no)
			(net "PCIE_IOM_TO_COMP_8_DP")
			(clearance 0.1651)
			(thermal_gap 0.1651)
		)
		(pad "F2" thru_hole circle
			(at 1.800098 -7.400036 180)
			(size 0.762 0.762)
			(drill 0.359918)
			(layers "*.Cu" "*.Mask")
			(remove_unused_layers no)
			(net "PCIE_IOM_TO_COMP_9_DP")
			(clearance 0.1651)
			(thermal_gap 0.1651)
		)
		(pad "F3" thru_hole circle
			(at 3.599942 -8.599932 180)
			(size 0.762 0.762)
			(drill 0.359918)
			(layers "*.Cu" "*.Mask")
			(remove_unused_layers no)
			(net "PCIE_IOM_TO_COMP_10_DP")
			(clearance 0.1651)
			(thermal_gap 0.1651)
		)
		(pad "F4" thru_hole circle
			(at 5.40004 -7.400036 180)
			(size 0.762 0.762)
			(drill 0.359918)
			(layers "*.Cu" "*.Mask")
			(remove_unused_layers no)
			(net "PCIE_IOM_TO_COMP_11_DP")
			(clearance 0.1651)
			(thermal_gap 0.1651)
		)
		(pad "F5" thru_hole circle
			(at 7.199884 -8.599932 180)
			(size 0.762 0.762)
			(drill 0.359918)
			(layers "*.Cu" "*.Mask")
			(remove_unused_layers no)
			(net "PCIE_IOM_TO_COMP_12_DP")
			(clearance 0.1651)
			(thermal_gap 0.1651)
		)
		(pad "F6" thru_hole circle
			(at 8.999982 -7.400036 180)
			(size 0.762 0.762)
			(drill 0.359918)
			(layers "*.Cu" "*.Mask")
			(remove_unused_layers no)
			(net "PCIE_IOM_TO_COMP_13_DP")
			(clearance 0.1651)
			(thermal_gap 0.1651)
		)
		(pad "F7" thru_hole circle
			(at 10.80008 -8.599932 180)
			(size 0.762 0.762)
			(drill 0.359918)
			(layers "*.Cu" "*.Mask")
			(remove_unused_layers no)
			(net "PCIE_IOM_TO_COMP_14_DP")
			(clearance 0.1651)
			(thermal_gap 0.1651)
		)
		(pad "F8" thru_hole circle
			(at 12.599924 -7.400036 180)
			(size 0.762 0.762)
			(drill 0.359918)
			(layers "*.Cu" "*.Mask")
			(remove_unused_layers no)
			(net "PCIE_IOM_TO_COMP_15_DP")
			(clearance 0.1651)
			(thermal_gap 0.1651)
		)
		(pad "F9" thru_hole circle
			(at 21.599906 -8.599932 180)
			(size 0.762 0.762)
			(drill 0.359918)
			(layers "*.Cu" "*.Mask")
			(remove_unused_layers no)
			(net "PCIE_IOM_TO_COMP_16_DP")
			(clearance 0.1651)
			(thermal_gap 0.1651)
		)
		(pad "F10" thru_hole circle
			(at 23.400004 -7.400036 180)
			(size 0.762 0.762)
			(drill 0.359918)
			(layers "*.Cu" "*.Mask")
			(remove_unused_layers no)
			(net "PCIE_IOM_TO_COMP_17_DP")
			(clearance 0.1651)
			(thermal_gap 0.1651)
		)
		(pad "F11" thru_hole circle
			(at 25.200102 -8.599932 180)
			(size 0.762 0.762)
			(drill 0.359918)
			(layers "*.Cu" "*.Mask")
			(remove_unused_layers no)
			(net "PCIE_IOM_TO_COMP_18_DP")
			(clearance 0.1651)
			(thermal_gap 0.1651)
		)
		(pad "F12" thru_hole circle
			(at 26.999946 -7.400036 180)
			(size 0.762 0.762)
			(drill 0.359918)
			(layers "*.Cu" "*.Mask")
			(remove_unused_layers no)
			(net "PCIE_IOM_TO_COMP_19_DP")
			(clearance 0.1651)
			(thermal_gap 0.1651)
		)
		(pad "F13" thru_hole circle
			(at 28.800044 -8.599932 180)
			(size 0.762 0.762)
			(drill 0.359918)
			(layers "*.Cu" "*.Mask")
			(remove_unused_layers no)
			(net "PCIE_IOM_TO_COMP_20_DP")
			(clearance 0.1651)
			(thermal_gap 0.1651)
		)
		(pad "F14" thru_hole circle
			(at 30.599888 -7.400036 180)
			(size 0.762 0.762)
			(drill 0.359918)
			(layers "*.Cu" "*.Mask")
			(remove_unused_layers no)
			(net "PCIE_IOM_TO_COMP_21_DP")
			(clearance 0.1651)
			(thermal_gap 0.1651)
		)
		(pad "F15" thru_hole circle
			(at 32.399986 -8.599932 180)
			(size 0.762 0.762)
			(drill 0.359918)
			(layers "*.Cu" "*.Mask")
			(remove_unused_layers no)
			(net "PCIE_IOM_TO_COMP_22_DP")
			(clearance 0.1651)
			(thermal_gap 0.1651)
		)
		(pad "F16" thru_hole circle
			(at 34.200084 -7.400036 180)
			(size 0.762 0.762)
			(drill 0.359918)
			(layers "*.Cu" "*.Mask")
			(remove_unused_layers no)
			(net "PCIE_IOM_TO_COMP_23_DP")
			(clearance 0.1651)
			(thermal_gap 0.1651)
		)
		(pad "G1" thru_hole circle
			(at 0 -10.80008 180)
			(size 0.762 0.762)
			(drill 0.359918)
			(layers "*.Cu" "*.Mask")
			(remove_unused_layers no)
			(net "PCIE_COMP_TO_IOM_8_DN")
			(clearance 0.1651)
			(thermal_gap 0.1651)
		)
		(pad "G2" thru_hole circle
			(at 1.800098 -9.59993 180)
			(size 0.762 0.762)
			(drill 0.359918)
			(layers "*.Cu" "*.Mask")
			(remove_unused_layers no)
			(net "PCIE_COMP_TO_IOM_9_DN")
			(clearance 0.1651)
			(thermal_gap 0.1651)
		)
		(pad "G3" thru_hole circle
			(at 3.599942 -10.80008 180)
			(size 0.762 0.762)
			(drill 0.359918)
			(layers "*.Cu" "*.Mask")
			(remove_unused_layers no)
			(net "PCIE_COMP_TO_IOM_10_DN")
			(clearance 0.1651)
			(thermal_gap 0.1651)
		)
		(pad "G4" thru_hole circle
			(at 5.40004 -9.59993 180)
			(size 0.762 0.762)
			(drill 0.359918)
			(layers "*.Cu" "*.Mask")
			(remove_unused_layers no)
			(net "PCIE_COMP_TO_IOM_11_DN")
			(clearance 0.1651)
			(thermal_gap 0.1651)
		)
		(pad "G5" thru_hole circle
			(at 7.199884 -10.80008 180)
			(size 0.762 0.762)
			(drill 0.359918)
			(layers "*.Cu" "*.Mask")
			(remove_unused_layers no)
			(net "PCIE_COMP_TO_IOM_12_DN")
			(clearance 0.1651)
			(thermal_gap 0.1651)
		)
		(pad "G6" thru_hole circle
			(at 8.999982 -9.59993 180)
			(size 0.762 0.762)
			(drill 0.359918)
			(layers "*.Cu" "*.Mask")
			(remove_unused_layers no)
			(net "PCIE_COMP_TO_IOM_13_DN")
			(clearance 0.1651)
			(thermal_gap 0.1651)
		)
		(pad "G7" thru_hole circle
			(at 10.80008 -10.80008 180)
			(size 0.762 0.762)
			(drill 0.359918)
			(layers "*.Cu" "*.Mask")
			(remove_unused_layers no)
			(net "PCIE_COMP_TO_IOM_14_DN")
			(clearance 0.1651)
			(thermal_gap 0.1651)
		)
		(pad "G8" thru_hole circle
			(at 12.599924 -9.59993 180)
			(size 0.762 0.762)
			(drill 0.359918)
			(layers "*.Cu" "*.Mask")
			(remove_unused_layers no)
			(net "PCIE_COMP_TO_IOM_15_DN")
			(clearance 0.1651)
			(thermal_gap 0.1651)
		)
		(pad "G9" thru_hole circle
			(at 21.599906 -10.80008 180)
			(size 0.762 0.762)
			(drill 0.359918)
			(layers "*.Cu" "*.Mask")
			(remove_unused_layers no)
			(net "PCIE_COMP_TO_IOM_16_DN")
			(clearance 0.1651)
			(thermal_gap 0.1651)
		)
		(pad "G10" thru_hole circle
			(at 23.400004 -9.59993 180)
			(size 0.762 0.762)
			(drill 0.359918)
			(layers "*.Cu" "*.Mask")
			(remove_unused_layers no)
			(net "PCIE_COMP_TO_IOM_17_DN")
			(clearance 0.1651)
			(thermal_gap 0.1651)
		)
		(pad "G11" thru_hole circle
			(at 25.200102 -10.80008 180)
			(size 0.762 0.762)
			(drill 0.359918)
			(layers "*.Cu" "*.Mask")
			(remove_unused_layers no)
			(net "PCIE_COMP_TO_IOM_18_DN")
			(clearance 0.1651)
			(thermal_gap 0.1651)
		)
		(pad "G12" thru_hole circle
			(at 26.999946 -9.59993 180)
			(size 0.762 0.762)
			(drill 0.359918)
			(layers "*.Cu" "*.Mask")
			(remove_unused_layers no)
			(net "PCIE_COMP_TO_IOM_19_DN")
			(clearance 0.1651)
			(thermal_gap 0.1651)
		)
		(pad "G13" thru_hole circle
			(at 28.800044 -10.80008 180)
			(size 0.762 0.762)
			(drill 0.359918)
			(layers "*.Cu" "*.Mask")
			(remove_unused_layers no)
			(net "PCIE_COMP_TO_IOM_20_DN")
			(clearance 0.1651)
			(thermal_gap 0.1651)
		)
		(pad "G14" thru_hole circle
			(at 30.599888 -9.59993 180)
			(size 0.762 0.762)
			(drill 0.359918)
			(layers "*.Cu" "*.Mask")
			(remove_unused_layers no)
			(net "PCIE_COMP_TO_IOM_21_DN")
			(clearance 0.1651)
			(thermal_gap 0.1651)
		)
		(pad "G15" thru_hole circle
			(at 32.399986 -10.80008 180)
			(size 0.762 0.762)
			(drill 0.359918)
			(layers "*.Cu" "*.Mask")
			(remove_unused_layers no)
			(net "PCIE_COMP_TO_IOM_22_DN")
			(clearance 0.1651)
			(thermal_gap 0.1651)
		)
		(pad "G16" thru_hole circle
			(at 34.200084 -9.59993 180)
			(size 0.762 0.762)
			(drill 0.359918)
			(layers "*.Cu" "*.Mask")
			(remove_unused_layers no)
			(net "PCIE_COMP_TO_IOM_23_DN")
			(clearance 0.1651)
			(thermal_gap 0.1651)
		)
		(pad "GND1" thru_hole circle
			(at 0 -2.500122 180)
			(size 0.762 0.762)
			(drill 0.359918)
			(layers "*.Cu" "*.Mask")
			(remove_unused_layers no)
			(net "GND")
			(clearance 0.1651)
			(thermal_gap 0.1651)
		)
		(pad "GND2" thru_hole circle
			(at 0 -6.100064 180)
			(size 0.762 0.762)
			(drill 0.359918)
			(layers "*.Cu" "*.Mask")
			(remove_unused_layers no)
			(net "GND")
			(clearance 0.1651)
			(thermal_gap 0.1651)
		)
		(pad "GND3" thru_hole circle
			(at 0 -9.700006 180)
			(size 0.762 0.762)
			(drill 0.359918)
			(layers "*.Cu" "*.Mask")
			(remove_unused_layers no)
			(net "GND")
			(clearance 0.1651)
			(thermal_gap 0.1651)
		)
		(pad "GND4" thru_hole circle
			(at 0 -13.299948 180)
			(size 0.762 0.762)
			(drill 0.359918)
			(layers "*.Cu" "*.Mask")
			(remove_unused_layers no)
			(net "GND")
			(clearance 0.1651)
			(thermal_gap 0.1651)
		)
		(pad "GND5" thru_hole circle
			(at 1.800098 2.29997 180)
			(size 0.762 0.762)
			(drill 0.359918)
			(layers "*.Cu" "*.Mask")
			(remove_unused_layers no)
			(net "GND")
			(clearance 0.1651)
			(thermal_gap 0.1651)
		)
		(pad "GND6" thru_hole circle
			(at 1.800098 -1.299972 180)
			(size 0.762 0.762)
			(drill 0.359918)
			(layers "*.Cu" "*.Mask")
			(remove_unused_layers no)
			(net "GND")
			(clearance 0.1651)
			(thermal_gap 0.1651)
		)
		(pad "GND7" thru_hole circle
			(at 1.800098 -4.899914 180)
			(size 0.762 0.762)
			(drill 0.359918)
			(layers "*.Cu" "*.Mask")
			(remove_unused_layers no)
			(net "GND")
			(clearance 0.1651)
			(thermal_gap 0.1651)
		)
		(pad "GND8" thru_hole circle
			(at 1.800098 -8.50011 180)
			(size 0.762 0.762)
			(drill 0.359918)
			(layers "*.Cu" "*.Mask")
			(remove_unused_layers no)
			(net "GND")
			(clearance 0.1651)
			(thermal_gap 0.1651)
		)
		(pad "GND9" thru_hole circle
			(at 1.800098 -12.100052 180)
			(size 0.762 0.762)
			(drill 0.359918)
			(layers "*.Cu" "*.Mask")
			(remove_unused_layers no)
			(net "GND")
			(clearance 0.1651)
			(thermal_gap 0.1651)
		)
		(pad "GND10" thru_hole circle
			(at 3.599942 -2.500122 180)
			(size 0.762 0.762)
			(drill 0.359918)
			(layers "*.Cu" "*.Mask")
			(remove_unused_layers no)
			(net "GND")
			(clearance 0.1651)
			(thermal_gap 0.1651)
		)
		(pad "GND11" thru_hole circle
			(at 3.599942 -6.100064 180)
			(size 0.762 0.762)
			(drill 0.359918)
			(layers "*.Cu" "*.Mask")
			(remove_unused_layers no)
			(net "GND")
			(clearance 0.1651)
			(thermal_gap 0.1651)
		)
		(pad "GND12" thru_hole circle
			(at 3.599942 -9.700006 180)
			(size 0.762 0.762)
			(drill 0.359918)
			(layers "*.Cu" "*.Mask")
			(remove_unused_layers no)
			(net "GND")
			(clearance 0.1651)
			(thermal_gap 0.1651)
		)
		(pad "GND13" thru_hole circle
			(at 3.599942 -13.299948 180)
			(size 0.762 0.762)
			(drill 0.359918)
			(layers "*.Cu" "*.Mask")
			(remove_unused_layers no)
			(net "GND")
			(clearance 0.1651)
			(thermal_gap 0.1651)
		)
		(pad "GND14" thru_hole circle
			(at 5.40004 2.29997 180)
			(size 0.762 0.762)
			(drill 0.359918)
			(layers "*.Cu" "*.Mask")
			(remove_unused_layers no)
			(net "GND")
			(clearance 0.1651)
			(thermal_gap 0.1651)
		)
		(pad "GND15" thru_hole circle
			(at 5.40004 -1.299972 180)
			(size 0.762 0.762)
			(drill 0.359918)
			(layers "*.Cu" "*.Mask")
			(remove_unused_layers no)
			(net "GND")
			(clearance 0.1651)
			(thermal_gap 0.1651)
		)
		(pad "GND16" thru_hole circle
			(at 5.40004 -4.899914 180)
			(size 0.762 0.762)
			(drill 0.359918)
			(layers "*.Cu" "*.Mask")
			(remove_unused_layers no)
			(net "GND")
			(clearance 0.1651)
			(thermal_gap 0.1651)
		)
		(pad "GND17" thru_hole circle
			(at 5.40004 -8.50011 180)
			(size 0.762 0.762)
			(drill 0.359918)
			(layers "*.Cu" "*.Mask")
			(remove_unused_layers no)
			(net "GND")
			(clearance 0.1651)
			(thermal_gap 0.1651)
		)
		(pad "GND18" thru_hole circle
			(at 5.40004 -12.100052 180)
			(size 0.762 0.762)
			(drill 0.359918)
			(layers "*.Cu" "*.Mask")
			(remove_unused_layers no)
			(net "GND")
			(clearance 0.1651)
			(thermal_gap 0.1651)
		)
		(pad "GND19" thru_hole circle
			(at 7.199884 -2.500122 180)
			(size 0.762 0.762)
			(drill 0.359918)
			(layers "*.Cu" "*.Mask")
			(remove_unused_layers no)
			(net "GND")
			(clearance 0.1651)
			(thermal_gap 0.1651)
		)
		(pad "GND20" thru_hole circle
			(at 7.199884 -6.100064 180)
			(size 0.762 0.762)
			(drill 0.359918)
			(layers "*.Cu" "*.Mask")
			(remove_unused_layers no)
			(net "GND")
			(clearance 0.1651)
			(thermal_gap 0.1651)
		)
		(pad "GND21" thru_hole circle
			(at 7.199884 -9.700006 180)
			(size 0.762 0.762)
			(drill 0.359918)
			(layers "*.Cu" "*.Mask")
			(remove_unused_layers no)
			(net "GND")
			(clearance 0.1651)
			(thermal_gap 0.1651)
		)
		(pad "GND22" thru_hole circle
			(at 7.199884 -13.299948 180)
			(size 0.762 0.762)
			(drill 0.359918)
			(layers "*.Cu" "*.Mask")
			(remove_unused_layers no)
			(net "GND")
			(clearance 0.1651)
			(thermal_gap 0.1651)
		)
		(pad "GND23" thru_hole circle
			(at 8.999982 2.29997 180)
			(size 0.762 0.762)
			(drill 0.359918)
			(layers "*.Cu" "*.Mask")
			(remove_unused_layers no)
			(net "GND")
			(clearance 0.1651)
			(thermal_gap 0.1651)
		)
		(pad "GND24" thru_hole circle
			(at 8.999982 -1.299972 180)
			(size 0.762 0.762)
			(drill 0.359918)
			(layers "*.Cu" "*.Mask")
			(remove_unused_layers no)
			(net "GND")
			(clearance 0.1651)
			(thermal_gap 0.1651)
		)
		(pad "GND25" thru_hole circle
			(at 8.999982 -4.899914 180)
			(size 0.762 0.762)
			(drill 0.359918)
			(layers "*.Cu" "*.Mask")
			(remove_unused_layers no)
			(net "GND")
			(clearance 0.1651)
			(thermal_gap 0.1651)
		)
		(pad "GND26" thru_hole circle
			(at 8.999982 -8.50011 180)
			(size 0.762 0.762)
			(drill 0.359918)
			(layers "*.Cu" "*.Mask")
			(remove_unused_layers no)
			(net "GND")
			(clearance 0.1651)
			(thermal_gap 0.1651)
		)
		(pad "GND27" thru_hole circle
			(at 8.999982 -12.100052 180)
			(size 0.762 0.762)
			(drill 0.359918)
			(layers "*.Cu" "*.Mask")
			(remove_unused_layers no)
			(net "GND")
			(clearance 0.1651)
			(thermal_gap 0.1651)
		)
		(pad "GND28" thru_hole circle
			(at 10.80008 -2.500122 180)
			(size 0.762 0.762)
			(drill 0.359918)
			(layers "*.Cu" "*.Mask")
			(remove_unused_layers no)
			(net "GND")
			(clearance 0.1651)
			(thermal_gap 0.1651)
		)
		(pad "GND29" thru_hole circle
			(at 10.80008 -6.100064 180)
			(size 0.762 0.762)
			(drill 0.359918)
			(layers "*.Cu" "*.Mask")
			(remove_unused_layers no)
			(net "GND")
			(clearance 0.1651)
			(thermal_gap 0.1651)
		)
		(pad "GND30" thru_hole circle
			(at 10.80008 -9.700006 180)
			(size 0.762 0.762)
			(drill 0.359918)
			(layers "*.Cu" "*.Mask")
			(remove_unused_layers no)
			(net "GND")
			(clearance 0.1651)
			(thermal_gap 0.1651)
		)
		(pad "GND31" thru_hole circle
			(at 10.80008 -13.299948 180)
			(size 0.762 0.762)
			(drill 0.359918)
			(layers "*.Cu" "*.Mask")
			(remove_unused_layers no)
			(net "GND")
			(clearance 0.1651)
			(thermal_gap 0.1651)
		)
		(pad "GND32" thru_hole circle
			(at 12.599924 2.29997 180)
			(size 0.762 0.762)
			(drill 0.359918)
			(layers "*.Cu" "*.Mask")
			(remove_unused_layers no)
			(net "GND")
			(clearance 0.1651)
			(thermal_gap 0.1651)
		)
		(pad "GND33" thru_hole circle
			(at 12.599924 -1.299972 180)
			(size 0.762 0.762)
			(drill 0.359918)
			(layers "*.Cu" "*.Mask")
			(remove_unused_layers no)
			(net "GND")
			(clearance 0.1651)
			(thermal_gap 0.1651)
		)
		(pad "GND34" thru_hole circle
			(at 12.599924 -4.899914 180)
			(size 0.762 0.762)
			(drill 0.359918)
			(layers "*.Cu" "*.Mask")
			(remove_unused_layers no)
			(net "GND")
			(clearance 0.1651)
			(thermal_gap 0.1651)
		)
	)
)
